(kicad_pcb
	(version 20241229)
	(generator "pcbnew")
	(generator_version "9.0")
	(general
		(thickness 1.6642)
		(legacy_teardrops no)
	)
	(paper "A3")
	(title_block
		(title "PolarFire SoM")
		(date "2025-07-22")
		(rev "1.1.4")
		(company "Antmicro Ltd")
		(comment 1 "www.antmicro.com")
		(comment 9 "footprints 242-245 of 470")
	)
	(layers
		(0 "F.Cu" mixed)
		(4 "In1.Cu" power)
		(6 "In2.Cu" signal)
		(8 "In3.Cu" power)
		(10 "In4.Cu" signal)
		(12 "In5.Cu" power)
		(14 "In6.Cu" power)
		(16 "In7.Cu" signal)
		(18 "In8.Cu" power)
		(20 "In9.Cu" signal)
		(22 "In10.Cu" power)
		(24 "In11.Cu" signal)
		(26 "In12.Cu" signal)
		(2 "B.Cu" mixed)
		(9 "F.Adhes" user "F.Adhesive")
		(11 "B.Adhes" user "B.Adhesive")
		(13 "F.Paste" user)
		(15 "B.Paste" user)
		(5 "F.SilkS" user "F.Silkscreen")
		(7 "B.SilkS" user "B.Silkscreen")
		(1 "F.Mask" user)
		(3 "B.Mask" user)
		(17 "Dwgs.User" user "User.Drawings")
		(19 "Cmts.User" user "User.Comments")
		(21 "Eco1.User" user "User.Eco1")
		(23 "Eco2.User" user "User.Eco2")
		(25 "Edge.Cuts" user)
		(27 "Margin" user)
		(31 "F.CrtYd" user "F.Courtyard")
		(29 "B.CrtYd" user "B.Courtyard")
		(35 "F.Fab" user)
		(33 "B.Fab" user)
	)
	(footprint "antmicro-footprints:R_0603_1608Metric"
		(layer "B.Cu")
		(at 199.114212 146.469061 -45)
		(descr "Resistor SMD 0603")
		(tags "resistor SMD 0603")
		(property "Reference" "R62"
			(at 0.117894 1.552206 315)
			(layer "B.SilkS")
			(effects
				(font
					(size 0.7 0.7)
					(thickness 0.15)
				)
				(justify left bottom mirror)
			)
		)
		(property "Value" "R_0R_22.4A_0603"
			(at 0 -1.6 135)
			(layer "B.Fab")
			(hide yes)
			(effects
				(font
					(size 0.7 0.7)
					(thickness 0.15)
				)
				(justify left bottom mirror)
			)
		)
		(property "Datasheet" "https://fscdn.rohm.com/en/products/databook/datasheet/passive/resistor/chip_resistor/pmr-jpw-e.pdf"
			(at 0 0 315)
			(layer "F.Fab")
			(hide yes)
			(effects
				(font
					(size 1.27 1.27)
					(thickness 0.15)
				)
			)
		)
		(property "Description" "SMD Chip Resistor"
			(at 0 0 315)
			(layer "F.Fab")
			(hide yes)
			(effects
				(font
					(size 1.27 1.27)
					(thickness 0.15)
				)
			)
		)
		(property "Author" "Antmicro"
			(at -45.250064 183.694805 0)
			(layer "B.Fab")
			(hide yes)
			(effects
				(font
					(size 1 1)
					(thickness 0.15)
				)
				(justify mirror)
			)
		)
		(property "DNP" "DNP"
			(at -45.250064 183.694805 0)
			(layer "B.Fab")
			(hide yes)
			(effects
				(font
					(size 1 1)
					(thickness 0.15)
				)
				(justify mirror)
			)
		)
		(property "License" "Apache-2.0"
			(at -45.250064 183.694805 0)
			(layer "B.Fab")
			(hide yes)
			(effects
				(font
					(size 1 1)
					(thickness 0.15)
				)
				(justify mirror)
			)
		)
		(property "MPN" "PMR03EZPJ000"
			(at -45.250064 183.694805 0)
			(layer "B.Fab")
			(hide yes)
			(effects
				(font
					(size 1 1)
					(thickness 0.15)
				)
				(justify mirror)
			)
		)
		(property "Manufacturer" "ROHM Semiconductor"
			(at -45.250064 183.694805 0)
			(layer "B.Fab")
			(hide yes)
			(effects
				(font
					(size 1 1)
					(thickness 0.15)
				)
				(justify mirror)
			)
		)
		(property "Max. Curr." "22.4A"
			(at -45.250064 183.694805 0)
			(layer "B.Fab")
			(hide yes)
			(effects
				(font
					(size 1 1)
					(thickness 0.15)
				)
				(justify mirror)
			)
		)
		(property "Public" ""
			(at -45.250064 183.694805 0)
			(layer "B.Fab")
			(hide yes)
			(effects
				(font
					(size 1 1)
					(thickness 0.15)
				)
				(justify mirror)
			)
		)
		(property "Tolerance" "template_tolerance"
			(at -45.250064 183.694805 0)
			(layer "B.Fab")
			(hide yes)
			(effects
				(font
					(size 1 1)
					(thickness 0.15)
				)
				(justify mirror)
			)
		)
		(property "Val" "0R"
			(at -45.250064 183.694805 0)
			(layer "B.Fab")
			(hide yes)
			(effects
				(font
					(size 1 1)
					(thickness 0.15)
				)
				(justify mirror)
			)
		)
		(sheetname "/Bottom Connector/")
		(sheetfile "bottom-connector.kicad_sch")
		(attr smd dnp)
		(fp_line
			(start -0.15 0.4)
			(end 0.15 0.4)
			(stroke
				(width 0.15)
				(type solid)
			)
			(layer "B.SilkS")
		)
		(fp_line
			(start -0.15 -0.4)
			(end 0.15 -0.4)
			(stroke
				(width 0.15)
				(type solid)
			)
			(layer "B.SilkS")
		)
		(fp_poly
			(pts
				(xy -1.25 0.65) (xy 1.25 0.65) (xy 1.25 -0.65) (xy -1.25 -0.65)
			)
			(stroke
				(width 0.05)
				(type solid)
			)
			(fill no)
			(layer "B.CrtYd")
		)
		(fp_poly
			(pts
				(xy -0.8 0.4) (xy 0.8 0.4) (xy 0.8 -0.4) (xy -0.8 -0.4)
			)
			(stroke
				(width 0.15)
				(type solid)
			)
			(fill no)
			(layer "B.Fab")
		)
		(fp_text user "Author: Antmicro"
			(at -1.25 -4.9 135)
			(layer "B.Fab")
			(effects
				(font
					(size 0.7 0.7)
					(thickness 0.15)
				)
				(justify left bottom mirror)
			)
		)
		(fp_text user "License: Apache-2.0"
			(at -1.249999 -5.9 135)
			(layer "B.Fab")
			(effects
				(font
					(size 0.7 0.7)
					(thickness 0.15)
				)
				(justify left bottom mirror)
			)
		)
		(fp_text user "${REFERENCE}"
			(at -1.25 -3.898 135)
			(layer "B.Fab")
			(effects
				(font
					(size 0.7 0.7)
					(thickness 0.15)
				)
				(justify left bottom mirror)
			)
		)
		(pad "1" smd roundrect
			(at -0.7 0 315)
			(size 0.8 1)
			(layers "B.Cu" "B.Mask" "B.Paste")
			(roundrect_rratio 0.2)
			(net 90 "+5V")
			(pintype "passive")
		)
		(pad "2" smd roundrect
			(at 0.7 0 315)
			(size 0.8 1)
			(layers "B.Cu" "B.Mask" "B.Paste")
			(roundrect_rratio 0.2)
			(net 410 "Net-(Q3-D)")
			(pintype "passive")
		)
	)
	(footprint "antmicro-footprints:C_0402_1005Metric"
		(layer "B.Cu")
		(at 184.4 129.25)
		(descr "Capacitor SMD 0402")
		(tags "capacitor SMD 0402")
		(property "Reference" "C148"
			(at -3.75 0.3 0)
			(layer "B.SilkS")
			(effects
				(font
					(size 0.7 0.7)
					(thickness 0.15)
				)
				(justify right bottom mirror)
			)
		)
		(property "Value" "C_1u_0402"
			(at -1.022927 -2.155213 0)
			(layer "B.Fab")
			(hide yes)
			(effects
				(font
					(size 0.7 0.7)
					(thickness 0.15)
				)
				(justify right bottom mirror)
			)
		)
		(property "Datasheet" "https://product.tdk.com/en/search/capacitor/ceramic/mlcc/info?part_no=C1005X6S1A105K050BC"
			(at 0 0 0)
			(layer "F.Fab")
			(hide yes)
			(effects
				(font
					(size 1.27 1.27)
					(thickness 0.15)
				)
			)
		)
		(property "Description" "SMD Multilayer Ceramic Capacitor, 1 µF, 10 V, 0402 [1005 Metric], ± 10%, X6S, C"
			(at 0 0 0)
			(layer "F.Fab")
			(hide yes)
			(effects
				(font
					(size 1.27 1.27)
					(thickness 0.15)
				)
			)
		)
		(property "Author" "Antmicro"
			(at 0 0 0)
			(layer "B.Fab")
			(hide yes)
			(effects
				(font
					(size 1 1)
					(thickness 0.15)
				)
				(justify mirror)
			)
		)
		(property "Dielectric" "X5R"
			(at 0 0 0)
			(layer "B.Fab")
			(hide yes)
			(effects
				(font
					(size 1 1)
					(thickness 0.15)
				)
				(justify mirror)
			)
		)
		(property "License" "Apache-2.0"
			(at 0 0 0)
			(layer "B.Fab")
			(hide yes)
			(effects
				(font
					(size 1 1)
					(thickness 0.15)
				)
				(justify mirror)
			)
		)
		(property "MPN" "C1005X6S1A105K050BC"
			(at 0 0 0)
			(layer "B.Fab")
			(hide yes)
			(effects
				(font
					(size 1 1)
					(thickness 0.15)
				)
				(justify mirror)
			)
		)
		(property "Manufacturer" "TDK"
			(at 0 0 0)
			(layer "B.Fab")
			(hide yes)
			(effects
				(font
					(size 1 1)
					(thickness 0.15)
				)
				(justify mirror)
			)
		)
		(property "Public" ""
			(at 0 0 0)
			(layer "B.Fab")
			(hide yes)
			(effects
				(font
					(size 1 1)
					(thickness 0.15)
				)
				(justify mirror)
			)
		)
		(property "Val" "1u"
			(at 0 0 0)
			(layer "B.Fab")
			(hide yes)
			(effects
				(font
					(size 1 1)
					(thickness 0.15)
				)
				(justify mirror)
			)
		)
		(property "Voltage" "16V"
			(at 0 0 0)
			(layer "B.Fab")
			(hide yes)
			(effects
				(font
					(size 1 1)
					(thickness 0.15)
				)
				(justify mirror)
			)
		)
		(sheetname "/LPDDR4/")
		(sheetfile "lpddr.kicad_sch")
		(attr smd)
		(fp_rect
			(start -0.925 0.47)
			(end 0.925 -0.47)
			(stroke
				(width 0.05)
				(type default)
			)
			(fill no)
			(layer "B.CrtYd")
		)
		(fp_line
			(start -0.494 -0.248)
			(end -0.494 0.25)
			(stroke
				(width 0.15)
				(type solid)
			)
			(layer "B.Fab")
		)
		(fp_line
			(start -0.494 0.25)
			(end 0.504 0.25)
			(stroke
				(width 0.15)
				(type solid)
			)
			(layer "B.Fab")
		)
		(fp_line
			(start 0.504 -0.248)
			(end -0.494 -0.248)
			(stroke
				(width 0.15)
				(type solid)
			)
			(layer "B.Fab")
		)
		(fp_line
			(start 0.504 0.25)
			(end 0.504 -0.248)
			(stroke
				(width 0.15)
				(type solid)
			)
			(layer "B.Fab")
		)
		(fp_text user "Author: Antmicro"
			(at -0.939 -3.399 180)
			(layer "B.Fab")
			(effects
				(font
					(size 0.7 0.7)
					(thickness 0.15)
				)
				(justify left bottom mirror)
			)
		)
		(fp_text user "${REFERENCE}"
			(at -0.939 -4.599 180)
			(layer "B.Fab")
			(effects
				(font
					(size 0.7 0.7)
					(thickness 0.15)
				)
				(justify left bottom mirror)
			)
		)
		(fp_text user "License: Apache-2.0"
			(at -0.939 -5.799 180)
			(layer "B.Fab")
			(effects
				(font
					(size 0.7 0.7)
					(thickness 0.15)
				)
				(justify left bottom mirror)
			)
		)
		(pad "1" smd roundrect
			(at -0.48 0)
			(size 0.59 0.64)
			(layers "B.Cu" "B.Mask" "B.Paste")
			(roundrect_rratio 0.25)
			(net 417 "GND")
			(pintype "passive")
		)
		(pad "2" smd roundrect
			(at 0.48 0)
			(size 0.59 0.64)
			(layers "B.Cu" "B.Mask" "B.Paste")
			(roundrect_rratio 0.25)
			(net 2 "+1V1")
			(pintype "passive")
		)
	)
	(footprint "antmicro-footprints:C_0402_1005Metric"
		(layer "B.Cu")
		(at 214.1925 132.697)
		(descr "Capacitor SMD 0402")
		(tags "capacitor SMD 0402")
		(property "Reference" "C69"
			(at 0.3875 1.423 0)
			(layer "B.SilkS")
			(effects
				(font
					(size 0.7 0.7)
					(thickness 0.15)
				)
				(justify right bottom mirror)
			)
		)
		(property "Value" "C_10u_0402"
			(at -1.022927 -2.155213 0)
			(layer "B.Fab")
			(hide yes)
			(effects
				(font
					(size 0.7 0.7)
					(thickness 0.15)
				)
				(justify right bottom mirror)
			)
		)
		(property "Datasheet" "https://www.yageo.com/en/Chart/Download/pdf/CC0402MRX5R5BB106"
			(at 0 0 0)
			(layer "F.Fab")
			(hide yes)
			(effects
				(font
					(size 1.27 1.27)
					(thickness 0.15)
				)
			)
		)
		(property "Description" "SMD Multilayer Ceramic Capacitor, 10 µF, 6.3 V, 0402 [1005 Metric], ± 20%, X5R, CC Series"
			(at 0 0 0)
			(layer "F.Fab")
			(hide yes)
			(effects
				(font
					(size 1.27 1.27)
					(thickness 0.15)
				)
			)
		)
		(property "Author" "Antmicro"
			(at 0 0 0)
			(layer "B.Fab")
			(hide yes)
			(effects
				(font
					(size 1 1)
					(thickness 0.15)
				)
				(justify mirror)
			)
		)
		(property "Dielectric" ""
			(at 0 0 0)
			(layer "B.Fab")
			(hide yes)
			(effects
				(font
					(size 1 1)
					(thickness 0.15)
				)
				(justify mirror)
			)
		)
		(property "License" "Apache-2.0"
			(at 0 0 0)
			(layer "B.Fab")
			(hide yes)
			(effects
				(font
					(size 1 1)
					(thickness 0.15)
				)
				(justify mirror)
			)
		)
		(property "MPN" "CC0402MRX5R5BB106"
			(at 0 0 0)
			(layer "B.Fab")
			(hide yes)
			(effects
				(font
					(size 1 1)
					(thickness 0.15)
				)
				(justify mirror)
			)
		)
		(property "Manufacturer" "YAGEO"
			(at 0 0 0)
			(layer "B.Fab")
			(hide yes)
			(effects
				(font
					(size 1 1)
					(thickness 0.15)
				)
				(justify mirror)
			)
		)
		(property "Public" ""
			(at 0 0 0)
			(layer "B.Fab")
			(hide yes)
			(effects
				(font
					(size 1 1)
					(thickness 0.15)
				)
				(justify mirror)
			)
		)
		(property "Val" "10u"
			(at 0 0 0)
			(layer "B.Fab")
			(hide yes)
			(effects
				(font
					(size 1 1)
					(thickness 0.15)
				)
				(justify mirror)
			)
		)
		(property "Voltage" ""
			(at 0 0 0)
			(layer "B.Fab")
			(hide yes)
			(effects
				(font
					(size 1 1)
					(thickness 0.15)
				)
				(justify mirror)
			)
		)
		(sheetname "/Memory/")
		(sheetfile "memory.kicad_sch")
		(attr smd)
		(fp_rect
			(start -0.925 0.47)
			(end 0.925 -0.47)
			(stroke
				(width 0.05)
				(type default)
			)
			(fill no)
			(layer "B.CrtYd")
		)
		(fp_line
			(start -0.494 -0.248)
			(end -0.494 0.25)
			(stroke
				(width 0.15)
				(type solid)
			)
			(layer "B.Fab")
		)
		(fp_line
			(start -0.494 0.25)
			(end 0.504 0.25)
			(stroke
				(width 0.15)
				(type solid)
			)
			(layer "B.Fab")
		)
		(fp_line
			(start 0.504 -0.248)
			(end -0.494 -0.248)
			(stroke
				(width 0.15)
				(type solid)
			)
			(layer "B.Fab")
		)
		(fp_line
			(start 0.504 0.25)
			(end 0.504 -0.248)
			(stroke
				(width 0.15)
				(type solid)
			)
			(layer "B.Fab")
		)
		(fp_text user "License: Apache-2.0"
			(at -0.939 -5.799 180)
			(layer "B.Fab")
			(effects
				(font
					(size 0.7 0.7)
					(thickness 0.15)
				)
				(justify left bottom mirror)
			)
		)
		(fp_text user "${REFERENCE}"
			(at -0.939 -4.599 180)
			(layer "B.Fab")
			(effects
				(font
					(size 0.7 0.7)
					(thickness 0.15)
				)
				(justify left bottom mirror)
			)
		)
		(fp_text user "Author: Antmicro"
			(at -0.939 -3.399 180)
			(layer "B.Fab")
			(effects
				(font
					(size 0.7 0.7)
					(thickness 0.15)
				)
				(justify left bottom mirror)
			)
		)
		(pad "1" smd roundrect
			(at -0.48 0)
			(size 0.59 0.64)
			(layers "B.Cu" "B.Mask" "B.Paste")
			(roundrect_rratio 0.25)
			(net 417 "GND")
			(pintype "passive")
		)
		(pad "2" smd roundrect
			(at 0.48 0)
			(size 0.59 0.64)
			(layers "B.Cu" "B.Mask" "B.Paste")
			(roundrect_rratio 0.25)
			(net 50 "+3V3")
			(pintype "passive")
		)
	)
	(footprint "antmicro-footprints:R_0402_1005Metric"
		(layer "B.Cu")
		(at 221.7175 144.895 90)
		(descr "Resistor SMD 0402")
		(tags "resistor SMD 0402")
		(property "Reference" "R144"
			(at 9.93 7.3275 270)
			(layer "B.SilkS")
			(effects
				(font
					(size 0.7 0.7)
					(thickness 0.15)
				)
				(justify left bottom mirror)
			)
		)
		(property "Value" "R_10k_0402"
			(at -1.011843 -1.772047 270)
			(layer "B.Fab")
			(hide yes)
			(effects
				(font
					(size 0.7 0.7)
					(thickness 0.15)
				)
				(justify left bottom mirror)
			)
		)
		(property "Datasheet" "https://www.bourns.com/docs/product-datasheets/cr.pdf"
			(at 0 0 90)
			(layer "F.Fab")
			(hide yes)
			(effects
				(font
					(size 1.27 1.27)
					(thickness 0.15)
				)
			)
		)
		(property "Description" "SMD Chip Resistor, 10 kohm, ± 1%, 62.5 mW, 0402 [1005 Metric], Thick Film, General Purpose"
			(at 0 0 90)
			(layer "F.Fab")
			(hide yes)
			(effects
				(font
					(size 1.27 1.27)
					(thickness 0.15)
				)
			)
		)
		(property "Author" "Antmicro"
			(at 366.6125 -76.8225 0)
			(layer "B.Fab")
			(hide yes)
			(effects
				(font
					(size 1 1)
					(thickness 0.15)
				)
				(justify mirror)
			)
		)
		(property "License" "Apache-2.0"
			(at 366.6125 -76.8225 0)
			(layer "B.Fab")
			(hide yes)
			(effects
				(font
					(size 1 1)
					(thickness 0.15)
				)
				(justify mirror)
			)
		)
		(property "MPN" "CR0402-FX-1002GLF"
			(at 366.6125 -76.8225 0)
			(layer "B.Fab")
			(hide yes)
			(effects
				(font
					(size 1 1)
					(thickness 0.15)
				)
				(justify mirror)
			)
		)
		(property "Manufacturer" "Bourns"
			(at 366.6125 -76.8225 0)
			(layer "B.Fab")
			(hide yes)
			(effects
				(font
					(size 1 1)
					(thickness 0.15)
				)
				(justify mirror)
			)
		)
		(property "Public" ""
			(at 366.6125 -76.8225 0)
			(layer "B.Fab")
			(hide yes)
			(effects
				(font
					(size 1 1)
					(thickness 0.15)
				)
				(justify mirror)
			)
		)
		(property "Tolerance" "1%"
			(at 366.6125 -76.8225 0)
			(layer "B.Fab")
			(hide yes)
			(effects
				(font
					(size 1 1)
					(thickness 0.15)
				)
				(justify mirror)
			)
		)
		(property "Val" "10k"
			(at 366.6125 -76.8225 0)
			(layer "B.Fab")
			(hide yes)
			(effects
				(font
					(size 1 1)
					(thickness 0.15)
				)
				(justify mirror)
			)
		)
		(sheetname "/WiFi_Bluetooth/")
		(sheetfile "wifi_bt.kicad_sch")
		(attr smd)
		(fp_rect
			(start -0.925 0.47)
			(end 0.925 -0.47)
			(stroke
				(width 0.05)
				(type default)
			)
			(fill no)
			(layer "B.CrtYd")
		)
		(fp_rect
			(start -0.5 0.25)
			(end 0.5 -0.25)
			(stroke
				(width 0.15)
				(type solid)
			)
			(fill no)
			(layer "B.Fab")
		)
		(fp_text user "${REFERENCE}"
			(at -0.95 -3.168 270)
			(layer "B.Fab")
			(effects
				(font
					(size 0.7 0.7)
					(thickness 0.15)
				)
				(justify left bottom mirror)
			)
		)
		(fp_text user "Author: Antmicro"
			(at -0.95 -4.169 270)
			(layer "B.Fab")
			(effects
				(font
					(size 0.7 0.7)
					(thickness 0.15)
				)
				(justify left bottom mirror)
			)
		)
		(fp_text user "License: Apache-2.0"
			(at -0.95 -5.169 270)
			(layer "B.Fab")
			(effects
				(font
					(size 0.7 0.7)
					(thickness 0.15)
				)
				(justify left bottom mirror)
			)
		)
		(pad "1" smd roundrect
			(at -0.48 0 90)
			(size 0.59 0.64)
			(layers "B.Cu" "B.Mask" "B.Paste")
			(roundrect_rratio 0.25)
			(net 171 "WL_REG_ON")
			(pintype "passive")
		)
		(pad "2" smd roundrect
			(at 0.48 0 90)
			(size 0.59 0.64)
			(layers "B.Cu" "B.Mask" "B.Paste")
			(roundrect_rratio 0.25)
			(net 50 "+3V3")
			(pintype "passive")
		)
	)
)
